# T6G (Grand Teton) — schematic netlist excerpt (pin names and nets, part order shuffled) for the footprints in the layout excerpt that follows; sources: Cadence DE-HDL packaged netlist, KiCad conversion of 04192023_DAF0TMB3IC0_F0TG_MB_C_brd_V02_OCP.brd

R8383  Q_RES  33 5% CHIP  pkg 0402LF  page 224 : A = PVDD11_S3_P1_PMALERT ; B = PVDD11_S3_P1_PMALERT_R
R4138  Q_RES  4.7K 5% CHIP  pkg 0402LF  page 125 : A = P3V3_AUX ; B = GPU_3V3IO_RSVD5_FFU_N

(kicad_pcb
	(version 20260206)
	(generator "pcbnew")
	(generator_version "10.0")
	(general
		(thickness 1.6)
		(legacy_teardrops no)
	)
	(paper "A4")
	(title_block
		(title "04192023_DAF0TMB3IC0_F0TG_MB_C_brd_V02_OCP.brd")
		(comment 1 "Grand Teton / footprints 3478-3479 of 8354")
	)
	(layers
		(0 "F.Cu" signal "TOP")
		(4 "In1.Cu" signal "GND")
		(6 "In2.Cu" signal "IN1")
		(8 "In3.Cu" signal "GND1")
		(10 "In4.Cu" signal "IN2")
		(12 "In5.Cu" signal "GND2")
		(14 "In6.Cu" signal "IN3")
		(16 "In7.Cu" signal "GND3")
		(18 "In8.Cu" signal "VCC")
		(20 "In9.Cu" signal "VCC1")
		(22 "In10.Cu" signal "GND4")
		(24 "In11.Cu" signal "IN4")
		(26 "In12.Cu" signal "GND5")
		(28 "In13.Cu" signal "IN5")
		(30 "In14.Cu" signal "GND6")
		(32 "In15.Cu" signal "IN6")
		(34 "In16.Cu" signal "GND7")
		(2 "B.Cu" signal "BOTTOM")
		(9 "F.Adhes" user "F.Adhesive")
		(11 "B.Adhes" user "B.Adhesive")
		(13 "F.Paste" user "Package Geometry/Pastemask Top")
		(15 "B.Paste" user "Package Geometry/Pastemask Bottom")
		(5 "F.SilkS" user "Ref Des/Silkscreen Top")
		(7 "B.SilkS" user "Ref Des/Silkscreen Bottom")
		(1 "F.Mask" user "Board Geometry/Soldermask Top")
		(3 "B.Mask" user "Board Geometry/Soldermask Bottom")
		(17 "Dwgs.User" user "User.Drawings")
		(19 "Cmts.User" user "User.Comments")
		(21 "Eco1.User" user "User.Eco1")
		(23 "Eco2.User" user "User.Eco2")
		(25 "Edge.Cuts" user "Board Geometry/Outline")
		(27 "Margin" user)
		(31 "F.CrtYd" user "Package Geometry/Place Bound Top")
		(29 "B.CrtYd" user "Package Geometry/Place Bound Bottom")
		(35 "F.Fab" user "Ref Des/Assembly Top")
		(33 "B.Fab" user "Ref Des/Assembly Bottom")
	)
	(footprint ""
		(layer "F.Cu")
		(at 159.07893 -352.668078 -90)
		(property "Reference" "R8383"
			(at 0 0 270)
			(layer "F.SilkS")
			(hide yes)
			(effects
				(font
					(size 1.27 1.27)
				)
			)
		)
		(property "Value" ""
			(at 0 0 270)
			(layer "F.Fab")
			(effects
				(font
					(size 1.27 1.27)
				)
			)
		)
		(duplicate_pad_numbers_are_jumpers no)
		(fp_line
			(start -0.7874 0.4064)
			(end -0.7874 -0.4064)
			(stroke
				(width 0.1524)
				(type default)
			)
			(layer "F.SilkS")
		)
		(fp_line
			(start 0.7874 0.4064)
			(end -0.7874 0.4064)
			(stroke
				(width 0.1524)
				(type default)
			)
			(layer "F.SilkS")
		)
		(fp_line
			(start -0.7874 -0.4064)
			(end 0.7874 -0.4064)
			(stroke
				(width 0.1524)
				(type default)
			)
			(layer "F.SilkS")
		)
		(fp_line
			(start 0.7874 -0.4064)
			(end 0.7874 0.4064)
			(stroke
				(width 0.1524)
				(type default)
			)
			(layer "F.SilkS")
		)
		(fp_line
			(start -0.67945 0.3048)
			(end -0.67945 -0.305054)
			(stroke
				(width 0.1)
				(type default)
			)
			(layer "F.Fab")
		)
		(fp_line
			(start -0.12065 0.3048)
			(end -0.67945 0.3048)
			(stroke
				(width 0.1)
				(type default)
			)
			(layer "F.Fab")
		)
		(fp_line
			(start 0.120396 0.3048)
			(end 0.120396 0.2794)
			(stroke
				(width 0.1)
				(type default)
			)
			(layer "F.Fab")
		)
		(fp_line
			(start 0.67945 0.3048)
			(end 0.120396 0.3048)
			(stroke
				(width 0.1)
				(type default)
			)
			(layer "F.Fab")
		)
		(fp_line
			(start -0.12065 0.2794)
			(end -0.12065 0.3048)
			(stroke
				(width 0.1)
				(type default)
			)
			(layer "F.Fab")
		)
		(fp_line
			(start 0.120396 0.2794)
			(end -0.12065 0.2794)
			(stroke
				(width 0.1)
				(type default)
			)
			(layer "F.Fab")
		)
		(fp_line
			(start -0.12065 -0.2794)
			(end 0.12065 -0.2794)
			(stroke
				(width 0.1)
				(type default)
			)
			(layer "F.Fab")
		)
		(fp_line
			(start 0.12065 -0.2794)
			(end 0.12065 -0.3048)
			(stroke
				(width 0.1)
				(type default)
			)
			(layer "F.Fab")
		)
		(fp_line
			(start 0.12065 -0.3048)
			(end 0.67945 -0.3048)
			(stroke
				(width 0.1)
				(type default)
			)
			(layer "F.Fab")
		)
		(fp_line
			(start 0.67945 -0.3048)
			(end 0.67945 0.3048)
			(stroke
				(width 0.1)
				(type default)
			)
			(layer "F.Fab")
		)
		(fp_line
			(start -0.67945 -0.305054)
			(end -0.12065 -0.305054)
			(stroke
				(width 0.1)
				(type default)
			)
			(layer "F.Fab")
		)
		(fp_line
			(start -0.12065 -0.305054)
			(end -0.12065 -0.2794)
			(stroke
				(width 0.1)
				(type default)
			)
			(layer "F.Fab")
		)
		(pad "1" smd circle
			(at -0.40005 0 270)
			(size 0 0)
			(layers "F.Cu" "F.Mask" "F.Paste")
			(net "PVDD11_S3_P1_PMALERT")
		)
		(pad "2" smd circle
			(at 0.40005 0 270)
			(size 0 0)
			(layers "F.Cu" "F.Mask" "F.Paste")
			(net "PVDD11_S3_P1_PMALERT_R")
		)
	)
	(footprint ""
		(layer "F.Cu")
		(at 305.175158 -439.877962 180)
		(property "Reference" "R4138"
			(at 0 0 180)
			(layer "F.SilkS")
			(hide yes)
			(effects
				(font
					(size 1.27 1.27)
				)
			)
		)
		(property "Value" ""
			(at 0 0 180)
			(layer "F.Fab")
			(effects
				(font
					(size 1.27 1.27)
				)
			)
		)
		(duplicate_pad_numbers_are_jumpers no)
		(fp_line
			(start 0.7874 0.4064)
			(end -0.7874 0.4064)
			(stroke
				(width 0.1524)
				(type default)
			)
			(layer "F.SilkS")
		)
		(fp_line
			(start 0.7874 -0.4064)
			(end 0.7874 0.4064)
			(stroke
				(width 0.1524)
				(type default)
			)
			(layer "F.SilkS")
		)
		(fp_line
			(start -0.7874 0.4064)
			(end -0.7874 -0.4064)
			(stroke
				(width 0.1524)
				(type default)
			)
			(layer "F.SilkS")
		)
		(fp_line
			(start -0.7874 -0.4064)
			(end 0.7874 -0.4064)
			(stroke
				(width 0.1524)
				(type default)
			)
			(layer "F.SilkS")
		)
		(fp_line
			(start 0.67945 0.3048)
			(end 0.120396 0.3048)
			(stroke
				(width 0.1)
				(type default)
			)
			(layer "F.Fab")
		)
		(fp_line
			(start 0.67945 -0.3048)
			(end 0.67945 0.3048)
			(stroke
				(width 0.1)
				(type default)
			)
			(layer "F.Fab")
		)
		(fp_line
			(start 0.12065 -0.2794)
			(end 0.12065 -0.3048)
			(stroke
				(width 0.1)
				(type default)
			)
			(layer "F.Fab")
		)
		(fp_line
			(start 0.12065 -0.3048)
			(end 0.67945 -0.3048)
			(stroke
				(width 0.1)
				(type default)
			)
			(layer "F.Fab")
		)
		(fp_line
			(start 0.120396 0.3048)
			(end 0.120396 0.2794)
			(stroke
				(width 0.1)
				(type default)
			)
			(layer "F.Fab")
		)
		(fp_line
			(start 0.120396 0.2794)
			(end -0.12065 0.2794)
			(stroke
				(width 0.1)
				(type default)
			)
			(layer "F.Fab")
		)
		(fp_line
			(start -0.12065 0.3048)
			(end -0.67945 0.3048)
			(stroke
				(width 0.1)
				(type default)
			)
			(layer "F.Fab")
		)
		(fp_line
			(start -0.12065 0.2794)
			(end -0.12065 0.3048)
			(stroke
				(width 0.1)
				(type default)
			)
			(layer "F.Fab")
		)
		(fp_line
			(start -0.12065 -0.2794)
			(end 0.12065 -0.2794)
			(stroke
				(width 0.1)
				(type default)
			)
			(layer "F.Fab")
		)
		(fp_line
			(start -0.12065 -0.305054)
			(end -0.12065 -0.2794)
			(stroke
				(width 0.1)
				(type default)
			)
			(layer "F.Fab")
		)
		(fp_line
			(start -0.67945 0.3048)
			(end -0.67945 -0.305054)
			(stroke
				(width 0.1)
				(type default)
			)
			(layer "F.Fab")
		)
		(fp_line
			(start -0.67945 -0.305054)
			(end -0.12065 -0.305054)
			(stroke
				(width 0.1)
				(type default)
			)
			(layer "F.Fab")
		)
		(pad "1" smd circle
			(at -0.40005 0 180)
			(size 0 0)
			(layers "F.Cu" "F.Mask" "F.Paste")
			(net "P3V3_AUX")
		)
		(pad "2" smd circle
			(at 0.40005 0 180)
			(size 0 0)
			(layers "F.Cu" "F.Mask" "F.Paste")
			(net "GPU_3V3IO_RSVD5_FFU_N")
		)
	)
)
